(kicad_pcb
	(version 20260206)
	(generator "pcbnew")
	(generator_version "10.0")
	(general
		(thickness 1.6)
		(legacy_teardrops no)
	)
	(paper "A4")
	(title_block
		(title "panther-plus-userver — 13130-1b_20150205.brd")
		(comment 1 "Honey Badger (Wiwynn) / footprint 894 of 1509 (DIMM1), pads 51-57 of 210")
	)
	(layers
		(0 "F.Cu" signal "TOP")
		(4 "In1.Cu" signal "L2")
		(6 "In2.Cu" signal "L3")
		(8 "In3.Cu" signal "L4")
		(10 "In4.Cu" signal "L5")
		(12 "In5.Cu" signal "L6")
		(14 "In6.Cu" signal "L7")
		(16 "In7.Cu" signal "L8")
		(18 "In8.Cu" signal "L9")
		(20 "In9.Cu" signal "L10")
		(22 "In10.Cu" signal "L11")
		(2 "B.Cu" signal "BOTTOM")
		(9 "F.Adhes" user "F.Adhesive")
		(11 "B.Adhes" user "B.Adhesive")
		(13 "F.Paste" user "Package Geometry/Pastemask Top")
		(15 "B.Paste" user "Package Geometry/Pastemask Bottom")
		(5 "F.SilkS" user "Ref Des/Silkscreen Top")
		(7 "B.SilkS" user "Ref Des/Silkscreen Bottom")
		(1 "F.Mask" user "Board Geometry/Soldermask Top")
		(3 "B.Mask" user "Board Geometry/Soldermask Bottom")
		(17 "Dwgs.User" user "User.Drawings")
		(19 "Cmts.User" user "User.Comments")
		(21 "Eco1.User" user "User.Eco1")
		(23 "Eco2.User" user "User.Eco2")
		(25 "Edge.Cuts" user "Board Geometry/Outline")
		(27 "Margin" user)
		(31 "F.CrtYd" user "Package Geometry/Place Bound Top")
		(29 "B.CrtYd" user "Package Geometry/Place Bound Bottom")
		(35 "F.Fab" user "Ref Des/Assembly Top")
		(33 "B.Fab" user "Ref Des/Assembly Bottom")
	)
	(footprint ""
		(layer "B.Cu")
		(at 158.500064 -66.699892 180)
		(property "Reference" "DIMM1"
			(at 0 0 0)
			(layer "B.SilkS")
			(hide yes)
			(effects
				(font
					(size 1.27 1.27)
				)
				(justify mirror)
			)
		)
		(property "Value" "DDR3-204P-142-COLAY-1-GP-U"
			(at 41.312338 -16.676878 180)
			(unlocked yes)
			(layer "B.Fab")
			(hide yes)
			(effects
				(font
					(size 1.016 1.016)
					(thickness 0.1524)
				)
				(justify mirror)
			)
		)
		(property "Device Type" "AS0A626-J8R6-7H-COLAY-1"
			(at 41.312338 -18.200878 180)
			(unlocked yes)
			(layer "B.Fab")
			(hide yes)
			(effects
				(font
					(size 1.016 1.016)
					(thickness 0.1524)
				)
				(justify mirror)
			)
		)
		(duplicate_pad_numbers_are_jumpers no)
		(pad "49" smd custom
			(at -17.249902 -4.100068)
			(size 0.1143 0.1143)
			(layers "B.Cu" "B.Mask" "B.Paste")
			(net "M_A_DQ18")
			(options
				(clearance outline)
				(anchor circle)
			)
			(primitives
				(gr_poly
					(pts
						(xy 0 -0.9017) (xy -0.03175 -0.89916) (xy -0.0635 -0.889) (xy -0.09144 -0.87376) (xy -0.11684 -0.85344)
						(xy -0.13716 -0.82804) (xy -0.1524 -0.8001) (xy -0.16256 -0.76835) (xy -0.1651 -0.7366) (xy -0.1651 -0.44958)
						(xy -0.17272 -0.44196) (xy -0.19812 -0.4064) (xy -0.2032 -0.39624) (xy -0.20701 -0.38735) (xy -0.21209 -0.37719)
						(xy -0.2159 -0.36703) (xy -0.21844 -0.35687) (xy -0.22225 -0.34544) (xy -0.22352 -0.33528) (xy -0.22606 -0.32512)
						(xy -0.22733 -0.31369) (xy -0.22733 -0.30353) (xy -0.2286 -0.2921) (xy -0.22733 -0.28067) (xy -0.22733 -0.27051)
						(xy -0.22606 -0.25908) (xy -0.22352 -0.24892) (xy -0.22225 -0.23876) (xy -0.21844 -0.22733) (xy -0.2159 -0.21717)
						(xy -0.21209 -0.20701) (xy -0.20701 -0.19685) (xy -0.2032 -0.18796) (xy -0.19812 -0.1778) (xy -0.17272 -0.14224)
						(xy -0.1651 -0.13462) (xy -0.1651 0.7366) (xy -0.16256 0.76835) (xy -0.1524 0.8001) (xy -0.13716 0.82804)
						(xy -0.11684 0.85344) (xy -0.09144 0.87376) (xy -0.0635 0.889) (xy -0.03175 0.89916) (xy 0 0.9017)
						(xy 0.03175 0.89916) (xy 0.0635 0.889) (xy 0.09144 0.87376) (xy 0.11684 0.85344) (xy 0.13716 0.82804)
						(xy 0.1524 0.8001) (xy 0.16256 0.76835) (xy 0.1651 0.7366) (xy 0.1651 -0.13462) (xy 0.17272 -0.14224)
						(xy 0.19812 -0.1778) (xy 0.2032 -0.18796) (xy 0.20701 -0.19685) (xy 0.21209 -0.20701) (xy 0.2159 -0.21717)
						(xy 0.21844 -0.22733) (xy 0.22225 -0.23876) (xy 0.22352 -0.24892) (xy 0.22606 -0.25908) (xy 0.22733 -0.27051)
						(xy 0.22733 -0.28067) (xy 0.2286 -0.2921) (xy 0.22733 -0.30353) (xy 0.22733 -0.31369) (xy 0.22606 -0.32512)
						(xy 0.22352 -0.33528) (xy 0.22225 -0.34544) (xy 0.21844 -0.35687) (xy 0.2159 -0.36703) (xy 0.21209 -0.37719)
						(xy 0.20701 -0.38735) (xy 0.2032 -0.39624) (xy 0.19812 -0.4064) (xy 0.17272 -0.44196) (xy 0.1651 -0.44958)
						(xy 0.1651 -0.7366) (xy 0.16256 -0.76835) (xy 0.1524 -0.8001) (xy 0.13716 -0.82804) (xy 0.11684 -0.85344)
						(xy 0.09144 -0.87376) (xy 0.0635 -0.889) (xy 0.03175 -0.89916)
					)
					(width 0)
					(fill yes)
				)
			)
		)
		(pad "50" smd custom
			(at -16.949928 4.100068)
			(size 0.1143 0.1143)
			(layers "B.Cu" "B.Mask" "B.Paste")
			(net "M_A_DQ23")
			(options
				(clearance outline)
				(anchor circle)
			)
			(primitives
				(gr_poly
					(pts
						(xy 0 -0.9017) (xy -0.03175 -0.89916) (xy -0.0635 -0.889) (xy -0.09144 -0.87376) (xy -0.11684 -0.85344)
						(xy -0.13716 -0.82804) (xy -0.1524 -0.8001) (xy -0.16256 -0.76835) (xy -0.1651 -0.7366) (xy -0.1651 0.13462)
						(xy -0.17272 0.14224) (xy -0.19812 0.1778) (xy -0.2032 0.18796) (xy -0.20701 0.19685) (xy -0.21209 0.20701)
						(xy -0.2159 0.21717) (xy -0.21844 0.22733) (xy -0.22225 0.23876) (xy -0.22352 0.24892) (xy -0.22606 0.25908)
						(xy -0.22733 0.27051) (xy -0.22733 0.28067) (xy -0.2286 0.2921) (xy -0.22733 0.30353) (xy -0.22733 0.31369)
						(xy -0.22606 0.32512) (xy -0.22352 0.33528) (xy -0.22225 0.34544) (xy -0.21844 0.35687) (xy -0.2159 0.36703)
						(xy -0.21209 0.37719) (xy -0.20701 0.38735) (xy -0.2032 0.39624) (xy -0.19812 0.4064) (xy -0.17272 0.44196)
						(xy -0.1651 0.44958) (xy -0.1651 0.7366) (xy -0.16256 0.76835) (xy -0.1524 0.8001) (xy -0.13716 0.82804)
						(xy -0.11684 0.85344) (xy -0.09144 0.87376) (xy -0.0635 0.889) (xy -0.03175 0.89916) (xy 0 0.9017)
						(xy 0.03175 0.89916) (xy 0.0635 0.889) (xy 0.09144 0.87376) (xy 0.11684 0.85344) (xy 0.13716 0.82804)
						(xy 0.1524 0.8001) (xy 0.16256 0.76835) (xy 0.1651 0.7366) (xy 0.1651 0.44958) (xy 0.17272 0.44196)
						(xy 0.19812 0.4064) (xy 0.2032 0.39624) (xy 0.20701 0.38735) (xy 0.21209 0.37719) (xy 0.2159 0.36703)
						(xy 0.21844 0.35687) (xy 0.22225 0.34544) (xy 0.22352 0.33528) (xy 0.22606 0.32512) (xy 0.22733 0.31369)
						(xy 0.22733 0.30353) (xy 0.2286 0.2921) (xy 0.22733 0.28067) (xy 0.22733 0.27051) (xy 0.22606 0.25908)
						(xy 0.22352 0.24892) (xy 0.22225 0.23876) (xy 0.21844 0.22733) (xy 0.2159 0.21717) (xy 0.21209 0.20701)
						(xy 0.20701 0.19685) (xy 0.2032 0.18796) (xy 0.19812 0.1778) (xy 0.17272 0.14224) (xy 0.1651 0.13462)
						(xy 0.1651 -0.7366) (xy 0.16256 -0.76835) (xy 0.1524 -0.8001) (xy 0.13716 -0.82804) (xy 0.11684 -0.85344)
						(xy 0.09144 -0.87376) (xy 0.0635 -0.889) (xy 0.03175 -0.89916)
					)
					(width 0)
					(fill yes)
				)
			)
		)
		(pad "51" smd custom
			(at -16.649954 -4.100068)
			(size 0.1143 0.1143)
			(layers "B.Cu" "B.Mask" "B.Paste")
			(net "M_A_DQ19")
			(options
				(clearance outline)
				(anchor circle)
			)
			(primitives
				(gr_poly
					(pts
						(xy 0 -0.9017) (xy -0.03175 -0.89916) (xy -0.0635 -0.889) (xy -0.09144 -0.87376) (xy -0.11684 -0.85344)
						(xy -0.13716 -0.82804) (xy -0.1524 -0.8001) (xy -0.16256 -0.76835) (xy -0.1651 -0.7366) (xy -0.1651 -0.19685)
						(xy -0.17272 -0.18923) (xy -0.17907 -0.18034) (xy -0.18669 -0.17145) (xy -0.19177 -0.16256) (xy -0.19812 -0.15367)
						(xy -0.20828 -0.13335) (xy -0.21971 -0.10287) (xy -0.22225 -0.09271) (xy -0.22479 -0.08128) (xy -0.22606 -0.07112)
						(xy -0.2286 -0.05969) (xy -0.2286 -0.01651) (xy -0.22606 -0.00508) (xy -0.22479 0.00508) (xy -0.22225 0.01651)
						(xy -0.21971 0.02667) (xy -0.20828 0.05715) (xy -0.19812 0.07747) (xy -0.19177 0.08636) (xy -0.18669 0.09525)
						(xy -0.17907 0.10414) (xy -0.17272 0.11303) (xy -0.1651 0.12065) (xy -0.1651 0.7366) (xy -0.16256 0.76835)
						(xy -0.1524 0.8001) (xy -0.13716 0.82804) (xy -0.11684 0.85344) (xy -0.09144 0.87376) (xy -0.0635 0.889)
						(xy -0.03175 0.89916) (xy 0 0.9017) (xy 0.03175 0.89916) (xy 0.0635 0.889) (xy 0.09144 0.87376)
						(xy 0.11684 0.85344) (xy 0.13716 0.82804) (xy 0.1524 0.8001) (xy 0.16256 0.76835) (xy 0.1651 0.7366)
						(xy 0.1651 0.11938) (xy 0.17272 0.11176) (xy 0.19812 0.0762) (xy 0.2032 0.06604) (xy 0.20701 0.05715)
						(xy 0.21209 0.04699) (xy 0.2159 0.03683) (xy 0.21844 0.02667) (xy 0.22225 0.01524) (xy 0.22352 0.00508)
						(xy 0.22606 -0.00508) (xy 0.22733 -0.01651) (xy 0.22733 -0.02667) (xy 0.2286 -0.0381) (xy 0.22733 -0.04953)
						(xy 0.22733 -0.05969) (xy 0.22606 -0.07112) (xy 0.22352 -0.08128) (xy 0.22225 -0.09144) (xy 0.21844 -0.10287)
						(xy 0.2159 -0.11303) (xy 0.21209 -0.12319) (xy 0.20701 -0.13335) (xy 0.2032 -0.14224) (xy 0.19812 -0.1524)
						(xy 0.17272 -0.18796) (xy 0.1651 -0.19558) (xy 0.1651 -0.7366) (xy 0.16256 -0.76835) (xy 0.1524 -0.8001)
						(xy 0.13716 -0.82804) (xy 0.11684 -0.85344) (xy 0.09144 -0.87376) (xy 0.0635 -0.889) (xy 0.03175 -0.89916)
					)
					(width 0)
					(fill yes)
				)
			)
		)
		(pad "52" smd custom
			(at -16.34998 4.100068)
			(size 0.1143 0.1143)
			(layers "B.Cu" "B.Mask" "B.Paste")
			(net "GND")
			(options
				(clearance outline)
				(anchor circle)
			)
			(primitives
				(gr_poly
					(pts
						(xy 0 -0.9017) (xy -0.03175 -0.89916) (xy -0.0635 -0.889) (xy -0.09144 -0.87376) (xy -0.11684 -0.85344)
						(xy -0.13716 -0.82804) (xy -0.1524 -0.8001) (xy -0.16256 -0.76835) (xy -0.1651 -0.7366) (xy -0.1651 -0.11938)
						(xy -0.17272 -0.11176) (xy -0.19812 -0.0762) (xy -0.2032 -0.06604) (xy -0.20701 -0.05715) (xy -0.21209 -0.04699)
						(xy -0.2159 -0.03683) (xy -0.21844 -0.02667) (xy -0.22225 -0.01524) (xy -0.22352 -0.00508) (xy -0.22606 0.00508)
						(xy -0.22733 0.01651) (xy -0.22733 0.02667) (xy -0.2286 0.0381) (xy -0.22733 0.04953) (xy -0.22733 0.05969)
						(xy -0.22606 0.07112) (xy -0.22352 0.08128) (xy -0.22225 0.09144) (xy -0.21844 0.10287) (xy -0.2159 0.11303)
						(xy -0.21209 0.12319) (xy -0.20701 0.13335) (xy -0.2032 0.14224) (xy -0.19812 0.1524) (xy -0.17272 0.18796)
						(xy -0.1651 0.19558) (xy -0.1651 0.7366) (xy -0.16256 0.76835) (xy -0.1524 0.8001) (xy -0.13716 0.82804)
						(xy -0.11684 0.85344) (xy -0.09144 0.87376) (xy -0.0635 0.889) (xy -0.03175 0.89916) (xy 0 0.9017)
						(xy 0.03175 0.89916) (xy 0.0635 0.889) (xy 0.09144 0.87376) (xy 0.11684 0.85344) (xy 0.13716 0.82804)
						(xy 0.1524 0.8001) (xy 0.16256 0.76835) (xy 0.1651 0.7366) (xy 0.1651 0.19685) (xy 0.17272 0.18923)
						(xy 0.17907 0.18034) (xy 0.18669 0.17145) (xy 0.19177 0.16256) (xy 0.19812 0.15367) (xy 0.20828 0.13335)
						(xy 0.21971 0.10287) (xy 0.22225 0.09271) (xy 0.22479 0.08128) (xy 0.22606 0.07112) (xy 0.2286 0.05969)
						(xy 0.2286 0.01651) (xy 0.22606 0.00508) (xy 0.22479 -0.00508) (xy 0.22225 -0.01651) (xy 0.21971 -0.02667)
						(xy 0.20828 -0.05715) (xy 0.19812 -0.07747) (xy 0.19177 -0.08636) (xy 0.18669 -0.09525) (xy 0.17907 -0.10414)
						(xy 0.17272 -0.11303) (xy 0.1651 -0.12065) (xy 0.1651 -0.7366) (xy 0.16256 -0.76835) (xy 0.1524 -0.8001)
						(xy 0.13716 -0.82804) (xy 0.11684 -0.85344) (xy 0.09144 -0.87376) (xy 0.0635 -0.889) (xy 0.03175 -0.89916)
					)
					(width 0)
					(fill yes)
				)
			)
		)
		(pad "53" smd custom
			(at -16.050006 -4.100068)
			(size 0.1143 0.1143)
			(layers "B.Cu" "B.Mask" "B.Paste")
			(net "GND")
			(options
				(clearance outline)
				(anchor circle)
			)
			(primitives
				(gr_poly
					(pts
						(xy 0 -0.9017) (xy -0.03175 -0.89916) (xy -0.0635 -0.889) (xy -0.09144 -0.87376) (xy -0.11684 -0.85344)
						(xy -0.13716 -0.82804) (xy -0.1524 -0.8001) (xy -0.16256 -0.76835) (xy -0.1651 -0.7366) (xy -0.1651 -0.44958)
						(xy -0.17272 -0.44196) (xy -0.19812 -0.4064) (xy -0.2032 -0.39624) (xy -0.20701 -0.38735) (xy -0.21209 -0.37719)
						(xy -0.2159 -0.36703) (xy -0.21844 -0.35687) (xy -0.22225 -0.34544) (xy -0.22352 -0.33528) (xy -0.22606 -0.32512)
						(xy -0.22733 -0.31369) (xy -0.22733 -0.30353) (xy -0.2286 -0.2921) (xy -0.22733 -0.28067) (xy -0.22733 -0.27051)
						(xy -0.22606 -0.25908) (xy -0.22352 -0.24892) (xy -0.22225 -0.23876) (xy -0.21844 -0.22733) (xy -0.2159 -0.21717)
						(xy -0.21209 -0.20701) (xy -0.20701 -0.19685) (xy -0.2032 -0.18796) (xy -0.19812 -0.1778) (xy -0.17272 -0.14224)
						(xy -0.1651 -0.13462) (xy -0.1651 0.7366) (xy -0.16256 0.76835) (xy -0.1524 0.8001) (xy -0.13716 0.82804)
						(xy -0.11684 0.85344) (xy -0.09144 0.87376) (xy -0.0635 0.889) (xy -0.03175 0.89916) (xy 0 0.9017)
						(xy 0.03175 0.89916) (xy 0.0635 0.889) (xy 0.09144 0.87376) (xy 0.11684 0.85344) (xy 0.13716 0.82804)
						(xy 0.1524 0.8001) (xy 0.16256 0.76835) (xy 0.1651 0.7366) (xy 0.1651 -0.13462) (xy 0.17272 -0.14224)
						(xy 0.19812 -0.1778) (xy 0.2032 -0.18796) (xy 0.20701 -0.19685) (xy 0.21209 -0.20701) (xy 0.2159 -0.21717)
						(xy 0.21844 -0.22733) (xy 0.22225 -0.23876) (xy 0.22352 -0.24892) (xy 0.22606 -0.25908) (xy 0.22733 -0.27051)
						(xy 0.22733 -0.28067) (xy 0.2286 -0.2921) (xy 0.22733 -0.30353) (xy 0.22733 -0.31369) (xy 0.22606 -0.32512)
						(xy 0.22352 -0.33528) (xy 0.22225 -0.34544) (xy 0.21844 -0.35687) (xy 0.2159 -0.36703) (xy 0.21209 -0.37719)
						(xy 0.20701 -0.38735) (xy 0.2032 -0.39624) (xy 0.19812 -0.4064) (xy 0.17272 -0.44196) (xy 0.1651 -0.44958)
						(xy 0.1651 -0.7366) (xy 0.16256 -0.76835) (xy 0.1524 -0.8001) (xy 0.13716 -0.82804) (xy 0.11684 -0.85344)
						(xy 0.09144 -0.87376) (xy 0.0635 -0.889) (xy 0.03175 -0.89916)
					)
					(width 0)
					(fill yes)
				)
			)
		)
		(pad "54" smd custom
			(at -15.750032 4.100068)
			(size 0.1143 0.1143)
			(layers "B.Cu" "B.Mask" "B.Paste")
			(net "M_A_DQ28")
			(options
				(clearance outline)
				(anchor circle)
			)
			(primitives
				(gr_poly
					(pts
						(xy 0 -0.9017) (xy -0.03175 -0.89916) (xy -0.0635 -0.889) (xy -0.09144 -0.87376) (xy -0.11684 -0.85344)
						(xy -0.13716 -0.82804) (xy -0.1524 -0.8001) (xy -0.16256 -0.76835) (xy -0.1651 -0.7366) (xy -0.1651 0.13462)
						(xy -0.17272 0.14224) (xy -0.19812 0.1778) (xy -0.2032 0.18796) (xy -0.20701 0.19685) (xy -0.21209 0.20701)
						(xy -0.2159 0.21717) (xy -0.21844 0.22733) (xy -0.22225 0.23876) (xy -0.22352 0.24892) (xy -0.22606 0.25908)
						(xy -0.22733 0.27051) (xy -0.22733 0.28067) (xy -0.2286 0.2921) (xy -0.22733 0.30353) (xy -0.22733 0.31369)
						(xy -0.22606 0.32512) (xy -0.22352 0.33528) (xy -0.22225 0.34544) (xy -0.21844 0.35687) (xy -0.2159 0.36703)
						(xy -0.21209 0.37719) (xy -0.20701 0.38735) (xy -0.2032 0.39624) (xy -0.19812 0.4064) (xy -0.17272 0.44196)
						(xy -0.1651 0.44958) (xy -0.1651 0.7366) (xy -0.16256 0.76835) (xy -0.1524 0.8001) (xy -0.13716 0.82804)
						(xy -0.11684 0.85344) (xy -0.09144 0.87376) (xy -0.0635 0.889) (xy -0.03175 0.89916) (xy 0 0.9017)
						(xy 0.03175 0.89916) (xy 0.0635 0.889) (xy 0.09144 0.87376) (xy 0.11684 0.85344) (xy 0.13716 0.82804)
						(xy 0.1524 0.8001) (xy 0.16256 0.76835) (xy 0.1651 0.7366) (xy 0.1651 0.44958) (xy 0.17272 0.44196)
						(xy 0.19812 0.4064) (xy 0.2032 0.39624) (xy 0.20701 0.38735) (xy 0.21209 0.37719) (xy 0.2159 0.36703)
						(xy 0.21844 0.35687) (xy 0.22225 0.34544) (xy 0.22352 0.33528) (xy 0.22606 0.32512) (xy 0.22733 0.31369)
						(xy 0.22733 0.30353) (xy 0.2286 0.2921) (xy 0.22733 0.28067) (xy 0.22733 0.27051) (xy 0.22606 0.25908)
						(xy 0.22352 0.24892) (xy 0.22225 0.23876) (xy 0.21844 0.22733) (xy 0.2159 0.21717) (xy 0.21209 0.20701)
						(xy 0.20701 0.19685) (xy 0.2032 0.18796) (xy 0.19812 0.1778) (xy 0.17272 0.14224) (xy 0.1651 0.13462)
						(xy 0.1651 -0.7366) (xy 0.16256 -0.76835) (xy 0.1524 -0.8001) (xy 0.13716 -0.82804) (xy 0.11684 -0.85344)
						(xy 0.09144 -0.87376) (xy 0.0635 -0.889) (xy 0.03175 -0.89916)
					)
					(width 0)
					(fill yes)
				)
			)
		)
		(pad "55" smd custom
			(at -15.450058 -4.100068)
			(size 0.1143 0.1143)
			(layers "B.Cu" "B.Mask" "B.Paste")
			(net "M_A_DQ24")
			(options
				(clearance outline)
				(anchor circle)
			)
			(primitives
				(gr_poly
					(pts
						(xy 0 -0.9017) (xy -0.03175 -0.89916) (xy -0.0635 -0.889) (xy -0.09144 -0.87376) (xy -0.11684 -0.85344)
						(xy -0.13716 -0.82804) (xy -0.1524 -0.8001) (xy -0.16256 -0.76835) (xy -0.1651 -0.7366) (xy -0.1651 -0.19685)
						(xy -0.17272 -0.18923) (xy -0.17907 -0.18034) (xy -0.18669 -0.17145) (xy -0.19177 -0.16256) (xy -0.19812 -0.15367)
						(xy -0.20828 -0.13335) (xy -0.21971 -0.10287) (xy -0.22225 -0.09271) (xy -0.22479 -0.08128) (xy -0.22606 -0.07112)
						(xy -0.2286 -0.05969) (xy -0.2286 -0.01651) (xy -0.22606 -0.00508) (xy -0.22479 0.00508) (xy -0.22225 0.01651)
						(xy -0.21971 0.02667) (xy -0.20828 0.05715) (xy -0.19812 0.07747) (xy -0.19177 0.08636) (xy -0.18669 0.09525)
						(xy -0.17907 0.10414) (xy -0.17272 0.11303) (xy -0.1651 0.12065) (xy -0.1651 0.7366) (xy -0.16256 0.76835)
						(xy -0.1524 0.8001) (xy -0.13716 0.82804) (xy -0.11684 0.85344) (xy -0.09144 0.87376) (xy -0.0635 0.889)
						(xy -0.03175 0.89916) (xy 0 0.9017) (xy 0.03175 0.89916) (xy 0.0635 0.889) (xy 0.09144 0.87376)
						(xy 0.11684 0.85344) (xy 0.13716 0.82804) (xy 0.1524 0.8001) (xy 0.16256 0.76835) (xy 0.1651 0.7366)
						(xy 0.1651 0.11938) (xy 0.17272 0.11176) (xy 0.19812 0.0762) (xy 0.2032 0.06604) (xy 0.20701 0.05715)
						(xy 0.21209 0.04699) (xy 0.2159 0.03683) (xy 0.21844 0.02667) (xy 0.22225 0.01524) (xy 0.22352 0.00508)
						(xy 0.22606 -0.00508) (xy 0.22733 -0.01651) (xy 0.22733 -0.02667) (xy 0.2286 -0.0381) (xy 0.22733 -0.04953)
						(xy 0.22733 -0.05969) (xy 0.22606 -0.07112) (xy 0.22352 -0.08128) (xy 0.22225 -0.09144) (xy 0.21844 -0.10287)
						(xy 0.2159 -0.11303) (xy 0.21209 -0.12319) (xy 0.20701 -0.13335) (xy 0.2032 -0.14224) (xy 0.19812 -0.1524)
						(xy 0.17272 -0.18796) (xy 0.1651 -0.19558) (xy 0.1651 -0.7366) (xy 0.16256 -0.76835) (xy 0.1524 -0.8001)
						(xy 0.13716 -0.82804) (xy 0.11684 -0.85344) (xy 0.09144 -0.87376) (xy 0.0635 -0.889) (xy 0.03175 -0.89916)
					)
					(width 0)
					(fill yes)
				)
			)
		)
	)
)
